# RDIMM DDR5 Tester — KiCad project settings (.kicad_pro: net classes, design rules, text variables)
{
  "board": {
    "3dviewports": [],
    "design_settings": {
      "defaults": {
        "apply_defaults_to_fp_fields": false,
        "apply_defaults_to_fp_shapes": false,
        "apply_defaults_to_fp_text": false,
        "board_outline_line_width": 0.1,
        "copper_line_width": 0.2,
        "copper_text_italic": false,
        "copper_text_size_h": 1.5,
        "copper_text_size_v": 1.5,
        "copper_text_thickness": 0.3,
        "copper_text_upright": false,
        "courtyard_line_width": 0.05,
        "dimension_precision": 4,
        "dimension_units": 3,
        "dimensions": {
          "arrow_length": 1270000,
          "extension_offset": 500000,
          "keep_text_aligned": true,
          "suppress_zeroes": false,
          "text_position": 0,
          "units_format": 1
        },
        "fab_line_width": 0.1,
        "fab_text_italic": false,
        "fab_text_size_h": 1.0,
        "fab_text_size_v": 1.0,
        "fab_text_thickness": 0.15,
        "fab_text_upright": false,
        "other_line_width": 0.1,
        "other_text_italic": false,
        "other_text_size_h": 1.0,
        "other_text_size_v": 1.0,
        "other_text_thickness": 0.15,
        "other_text_upright": false,
        "pads": {
          "drill": 0.0,
          "height": 1.0,
          "width": 0.8
        },
        "silk_line_width": 0.15,
        "silk_text_italic": false,
        "silk_text_size_h": 0.7,
        "silk_text_size_v": 0.7,
        "silk_text_thickness": 0.15,
        "silk_text_upright": false,
        "zones": {
          "45_degree_only": false,
          "min_clearance": 0.12
        }
      },
      "diff_pair_dimensions": [
        {
          "gap": 0.0,
          "via_gap": 0.0,
          "width": 0.0
        }
      ],
      "drc_exclusions": [],
      "meta": {
        "filename": "board_design_settings.json",
        "version": 2
      },
      "rule_severities": {
        "annular_width": "error",
        "clearance": "error",
        "connection_width": "warning",
        "copper_edge_clearance": "error",
        "copper_sliver": "warning",
        "courtyards_overlap": "error",
        "creepage": "error",
        "diff_pair_gap_out_of_range": "ignore",
        "diff_pair_uncoupled_length_too_long": "error",
        "drill_out_of_range": "error",
        "duplicate_footprints": "warning",
        "extra_footprint": "warning",
        "footprint": "error",
        "footprint_filters_mismatch": "ignore",
        "footprint_symbol_mismatch": "warning",
        "footprint_type_mismatch": "ignore",
        "hole_clearance": "error",
        "hole_near_hole": "error",
        "hole_to_hole": "error",
        "holes_co_located": "warning",
        "invalid_outline": "error",
        "isolated_copper": "warning",
        "item_on_disabled_layer": "error",
        "items_not_allowed": "error",
        "length_out_of_range": "error",
        "lib_footprint_issues": "warning",
        "lib_footprint_mismatch": "warning",
        "malformed_courtyard": "error",
        "microvia_drill_out_of_range": "error",
        "mirrored_text_on_front_layer": "warning",
        "missing_courtyard": "ignore",
        "missing_footprint": "warning",
        "net_conflict": "warning",
        "nonmirrored_text_on_back_layer": "warning",
        "npth_inside_courtyard": "warning",
        "padstack": "error",
        "pth_inside_courtyard": "warning",
        "shorting_items": "error",
        "silk_edge_clearance": "ignore",
        "silk_over_copper": "ignore",
        "silk_overlap": "ignore",
        "skew_out_of_range": "error",
        "solder_mask_bridge": "ignore",
        "starved_thermal": "error",
        "text_height": "warning",
        "text_on_edge_cuts": "error",
        "text_thickness": "warning",
        "through_hole_pad_without_hole": "error",
        "too_many_vias": "error",
        "track_angle": "error",
        "track_dangling": "warning",
        "track_segment_length": "error",
        "track_width": "error",
        "tracks_crossing": "error",
        "unconnected_items": "error",
        "unresolved_variable": "error",
        "via_dangling": "ignore",
        "zones_intersect": "error"
      },
      "rule_severitieslegacy_courtyards_overlap": true,
      "rule_severitieslegacy_no_courtyard_defined": false,
      "rules": {
        "allow_blind_buried_vias": false,
        "allow_microvias": false,
        "max_error": 0.005,
        "min_clearance": 0.1,
        "min_connection": 0.0,
        "min_copper_edge_clearance": 0.2,
        "min_groove_width": 0.0,
        "min_hole_clearance": 0.15,
        "min_hole_to_hole": 0.25,
        "min_microvia_diameter": 0.2,
        "min_microvia_drill": 0.1,
        "min_resolved_spokes": 2,
        "min_silk_clearance": 0.0,
        "min_text_height": 0.6,
        "min_text_thickness": 0.05,
        "min_through_hole_diameter": 0.1,
        "min_track_width": 0.1,
        "min_via_annular_width": 0.125,
        "min_via_diameter": 0.45,
        "solder_mask_to_copper_clearance": 0.0,
        "use_height_for_length_calcs": true
      },
      "teardrop_options": [
        {
          "td_onpthpad": true,
          "td_onroundshapesonly": false,
          "td_onsmdpad": true,
          "td_ontrackend": false,
          "td_onvia": true
        }
      ],
      "teardrop_parameters": [
        {
          "td_allow_use_two_tracks": true,
          "td_curve_segcount": 0,
          "td_height_ratio": 1.0,
          "td_length_ratio": 0.5,
          "td_maxheight": 2.0,
          "td_maxlen": 1.0,
          "td_on_pad_in_zone": false,
          "td_target_name": "td_round_shape",
          "td_width_to_size_filter_ratio": 0.9
        },
        {
          "td_allow_use_two_tracks": true,
          "td_curve_segcount": 0,
          "td_height_ratio": 1.0,
          "td_length_ratio": 0.5,
          "td_maxheight": 2.0,
          "td_maxlen": 1.0,
          "td_on_pad_in_zone": false,
          "td_target_name": "td_rect_shape",
          "td_width_to_size_filter_ratio": 0.9
        },
        {
          "td_allow_use_two_tracks": true,
          "td_curve_segcount": 0,
          "td_height_ratio": 1.0,
          "td_length_ratio": 0.5,
          "td_maxheight": 2.0,
          "td_maxlen": 1.0,
          "td_on_pad_in_zone": false,
          "td_target_name": "td_track_end",
          "td_width_to_size_filter_ratio": 0.9
        }
      ],
      "track_widths": [
        0.0,
        0.1,
        0.107,
        0.114,
        0.15,
        0.177,
        0.182,
        0.198,
        0.201,
        0.256,
        0.4,
        0.6,
        2.0
      ],
      "tuning_pattern_settings": {
        "diff_pair_defaults": {
          "corner_radius_percentage": 80,
          "corner_style": 1,
          "max_amplitude": 1.0,
          "min_amplitude": 0.2,
          "single_sided": false,
          "spacing": 1.0
        },
        "diff_pair_skew_defaults": {
          "corner_radius_percentage": 80,
          "corner_style": 1,
          "max_amplitude": 1.0,
          "min_amplitude": 0.2,
          "single_sided": false,
          "spacing": 0.6
        },
        "single_track_defaults": {
          "corner_radius_percentage": 80,
          "corner_style": 1,
          "max_amplitude": 1.0,
          "min_amplitude": 0.2,
          "single_sided": false,
          "spacing": 0.6
        }
      },
      "via_dimensions": [
        {
          "diameter": 0.0,
          "drill": 0.0
        },
        {
          "diameter": 0.45,
          "drill": 0.1
        }
      ],
      "zones_allow_external_fillets": false,
      "zones_use_no_outline": true
    },
    "ipc2581": {
      "dist": "",
      "distpn": "",
      "internal_id": "",
      "mfg": "",
      "mpn": ""
    },
    "layer_pairs": [],
    "layer_presets": [],
    "viewports": []
  },
  "boards": [],
  "cvpcb": {
    "equivalence_files": []
  },
  "erc": {
    "erc_exclusions": [],
    "meta": {
      "version": 0
    },
    "pin_map": [
      [
        0,
        0,
        0,
        0,
        0,
        0,
        1,
        0,
        0,
        0,
        0,
        2
      ],
      [
        0,
        2,
        0,
        1,
        0,
        0,
        1,
        0,
        2,
        2,
        2,
        2
      ],
      [
        0,
        0,
        0,
        0,
        0,
        0,
        1,
        0,
        1,
        0,
        1,
        2
      ],
      [
        0,
        1,
        0,
        0,
        0,
        0,
        1,
        1,
        2,
        1,
        1,
        2
      ],
      [
        0,
        0,
        0,
        0,
        0,
        0,
        1,
        0,
        0,
        0,
        0,
        2
      ],
      [
        0,
        0,
        0,
        0,
        0,
        0,
        0,
        0,
        0,
        0,
        0,
        2
      ],
      [
        1,
        1,
        1,
        1,
        1,
        0,
        1,
        1,
        1,
        1,
        1,
        2
      ],
      [
        0,
        0,
        0,
        1,
        0,
        0,
        1,
        0,
        0,
        0,
        0,
        2
      ],
      [
        0,
        2,
        1,
        2,
        0,
        0,
        1,
        0,
        2,
        2,
        2,
        2
      ],
      [
        0,
        2,
        0,
        1,
        0,
        0,
        1,
        0,
        2,
        0,
        0,
        2
      ],
      [
        0,
        2,
        1,
        1,
        0,
        0,
        1,
        0,
        2,
        0,
        0,
        2
      ],
      [
        2,
        2,
        2,
        2,
        2,
        2,
        2,
        2,
        2,
        2,
        2,
        2
      ]
    ],
    "rule_severities": {
      "bus_definition_conflict": "error",
      "bus_entry_needed": "error",
      "bus_to_bus_conflict": "error",
      "bus_to_net_conflict": "error",
      "conflicting_netclasses": "error",
      "different_unit_footprint": "error",
      "different_unit_net": "error",
      "duplicate_reference": "error",
      "duplicate_sheet_names": "error",
      "endpoint_off_grid": "warning",
      "extra_units": "error",
      "footprint_filter": "ignore",
      "footprint_link_issues": "warning",
      "four_way_junction": "ignore",
      "global_label_dangling": "ignore",
      "hier_label_mismatch": "error",
      "label_dangling": "error",
      "label_multiple_wires": "warning",
      "lib_symbol_issues": "ignore",
      "lib_symbol_mismatch": "warning",
      "missing_bidi_pin": "warning",
      "missing_input_pin": "warning",
      "missing_power_pin": "error",
      "missing_unit": "warning",
      "multiple_net_names": "ignore",
      "net_not_bus_member": "ignore",
      "no_connect_connected": "ignore",
      "no_connect_dangling": "warning",
      "pin_not_connected": "error",
      "pin_not_driven": "ignore",
      "pin_to_pin": "ignore",
      "power_pin_not_driven": "error",
      "same_local_global_label": "warning",
      "similar_label_and_power": "warning",
      "similar_labels": "warning",
      "similar_power": "warning",
      "simulation_model_issue": "ignore",
      "single_global_label": "ignore",
      "unannotated": "error",
      "unconnected_wire_endpoint": "warning",
      "undefined_netclass": "error",
      "unit_value_mismatch": "error",
      "unresolved_variable": "error",
      "wire_dangling": "error"
    }
  },
  "libraries": {
    "pinned_footprint_libs": [],
    "pinned_symbol_libs": []
  },
  "meta": {
    "filename": "data-center-rdimm-ddr5-tester.kicad_pro",
    "version": 3
  },
  "net_settings": {
    "classes": [
      {
        "bus_width": 12,
        "clearance": 0.1,
        "diff_pair_gap": 0.1,
        "diff_pair_via_gap": 0.25,
        "diff_pair_width": 0.1,
        "line_style": 0,
        "microvia_diameter": 0.3,
        "microvia_drill": 0.1,
        "name": "Default",
        "pcb_color": "rgba(0, 0, 0, 0.000)",
        "priority": 2147483647,
        "schematic_color": "rgba(0, 0, 0, 0.000)",
        "track_width": 0.1,
        "via_diameter": 0.45,
        "via_drill": 0.1,
        "wire_width": 6
      },
      {
        "bus_width": 12,
        "clearance": 0.1,
        "diff_pair_gap": 0.1,
        "diff_pair_width": 0.1,
        "line_style": 0,
        "microvia_diameter": 0.3,
        "microvia_drill": 0.1,
        "name": "100Ohm-diff",
        "pcb_color": "rgba(0, 0, 0, 0.000)",
        "priority": 0,
        "schematic_color": "rgba(0, 0, 0, 0.000)",
        "track_width": 0.1,
        "via_diameter": 0.45,
        "via_drill": 0.1,
        "wire_width": 6
      },
      {
        "bus_width": 12,
        "clearance": 0.2,
        "diff_pair_gap": 0.1,
        "diff_pair_width": 0.1,
        "line_style": 0,
        "microvia_diameter": 0.3,
        "microvia_drill": 0.1,
        "name": "12V",
        "pcb_color": "rgba(0, 0, 0, 0.000)",
        "priority": 1,
        "schematic_color": "rgba(0, 0, 0, 0.000)",
        "track_width": 0.1,
        "via_diameter": 0.45,
        "via_drill": 0.1,
        "wire_width": 6
      },
      {
        "bus_width": 12,
        "clearance": 0.1,
        "diff_pair_gap": 0.1,
        "diff_pair_width": 0.1,
        "line_style": 0,
        "microvia_diameter": 0.3,
        "microvia_drill": 0.1,
        "name": "40Ohm-se_DQ",
        "pcb_color": "rgba(0, 0, 0, 0.000)",
        "priority": 2,
        "schematic_color": "rgba(0, 0, 0, 0.000)",
        "track_width": 0.1,
        "via_diameter": 0.45,
        "via_drill": 0.1,
        "wire_width": 6
      },
      {
        "bus_width": 12,
        "clearance": 0.1,
        "diff_pair_gap": 0.1,
        "diff_pair_width": 0.1,
        "line_style": 0,
        "microvia_diameter": 0.3,
        "microvia_drill": 0.1,
        "name": "50Ohm-se",
        "pcb_color": "rgba(0, 0, 0, 0.000)",
        "priority": 3,
        "schematic_color": "rgba(0, 0, 0, 0.000)",
        "track_width": 0.1,
        "via_diameter": 0.45,
        "via_drill": 0.1,
        "wire_width": 6
      },
      {
        "bus_width": 12,
        "clearance": 0.1,
        "diff_pair_gap": 0.1,
        "diff_pair_width": 0.1,
        "line_style": 0,
        "microvia_diameter": 0.3,
        "microvia_drill": 0.1,
        "name": "80Ohm-diff_DQS",
        "pcb_color": "rgba(0, 0, 0, 0.000)",
        "priority": 4,
        "schematic_color": "rgba(0, 0, 0, 0.000)",
        "track_width": 0.1,
        "via_diameter": 0.45,
        "via_drill": 0.1,
        "wire_width": 6
      },
      {
        "bus_width": 12,
        "clearance": 0.1,
        "diff_pair_gap": 0.1,
        "diff_pair_width": 0.1,
        "line_style": 0,
        "microvia_diameter": 0.3,
        "microvia_drill": 0.1,
        "name": "85Ohm-diff_PCIe",
        "pcb_color": "rgba(0, 0, 0, 0.000)",
        "priority": 5,
        "schematic_color": "rgba(0, 0, 0, 0.000)",
        "track_width": 0.1,
        "via_diameter": 0.45,
        "via_drill": 0.1,
        "wire_width": 6
      },
      {
        "bus_width": 12,
        "clearance": 0.1,
        "diff_pair_gap": 0.1,
        "diff_pair_width": 0.1,
        "line_style": 0,
        "microvia_diameter": 0.3,
        "microvia_drill": 0.1,
        "name": "90Ohm-diff",
        "pcb_color": "rgba(0, 0, 0, 0.000)",
        "priority": 6,
        "schematic_color": "rgba(0, 0, 0, 0.000)",
        "track_width": 0.1,
        "via_diameter": 0.45,
        "via_drill": 0.1,
        "wire_width": 6
      },
      {
        "bus_width": 12,
        "clearance": 0.1,
        "diff_pair_gap": 0.25,
        "diff_pair_width": 0.2,
        "line_style": 0,
        "microvia_diameter": 0.3,
        "microvia_drill": 0.1,
        "name": "Supply",
        "pcb_color": "rgba(0, 0, 0, 0.000)",
        "priority": 7,
        "schematic_color": "rgba(0, 0, 0, 0.000)",
        "track_width": 0.1,
        "via_diameter": 0.45,
        "via_drill": 0.1,
        "wire_width": 6
      },
      {
        "bus_width": 12,
        "clearance": 0.15,
        "diff_pair_gap": 0.15,
        "diff_pair_width": 0.1,
        "line_style": 0,
        "microvia_diameter": 0.3,
        "microvia_drill": 0.1,
        "name": "tunning",
        "pcb_color": "rgba(0, 0, 0, 0.000)",
        "priority": 8,
        "schematic_color": "rgba(0, 0, 0, 0.000)",
        "track_width": 0.1,
        "via_diameter": 0.45,
        "via_drill": 0.1,
        "wire_width": 6
      }
    ],
    "meta": {
      "version": 4
    },
    "net_colors": {
      "GND": "rgb(0, 0, 255)"
    },
    "netclass_assignments": null,
    "netclass_patterns": [
      {
        "netclass": "100Ohm-diff",
        "pattern": "/Ethernet/ETH1_N"
      },
      {
        "netclass": "100Ohm-diff",
        "pattern": "/Ethernet/ETH1_P"
      },
      {
        "netclass": "100Ohm-diff",
        "pattern": "/Ethernet/ETH2_N"
      },
      {
        "netclass": "100Ohm-diff",
        "pattern": "/Ethernet/ETH2_P"
      },
      {
        "netclass": "100Ohm-diff",
        "pattern": "/Ethernet/ETH3_N"
      },
      {
        "netclass": "100Ohm-diff",
        "pattern": "/Ethernet/ETH3_P"
      },
      {
        "netclass": "100Ohm-diff",
        "pattern": "/Ethernet/ETH4_N"
      },
      {
        "netclass": "100Ohm-diff",
        "pattern": "/Ethernet/ETH4_P"
      },
      {
        "netclass": "100Ohm-diff",
        "pattern": "/FPGA bank 12/HyperRAM.CK_N"
      },
      {
        "netclass": "100Ohm-diff",
        "pattern": "/FPGA bank 12/HyperRAM.CK_P"
      },
      {
        "netclass": "100Ohm-diff",
        "pattern": "/FPGA bank 16/HDMI.CLK_N"
      },
      {
        "netclass": "100Ohm-diff",
        "pattern": "/FPGA bank 16/HDMI.CLK_P"
      },
      {
        "netclass": "100Ohm-diff",
        "pattern": "/FPGA bank 16/HDMI.D0_N"
      },
      {
        "netclass": "100Ohm-diff",
        "pattern": "/FPGA bank 16/HDMI.D0_P"
      },
      {
        "netclass": "100Ohm-diff",
        "pattern": "/FPGA bank 16/HDMI.D1_N"
      },
      {
        "netclass": "100Ohm-diff",
        "pattern": "/FPGA bank 16/HDMI.D1_P"
      },
      {
        "netclass": "100Ohm-diff",
        "pattern": "/FPGA bank 16/HDMI.D2_N"
      },
      {
        "netclass": "100Ohm-diff",
        "pattern": "/FPGA bank 16/HDMI.D2_P"
      },
      {
        "netclass": "100Ohm-diff",
        "pattern": "/HDMI + SD Card/HDMI_OUT_CONN*"
      },
      {
        "netclass": "12V",
        "pattern": "/Supply/12V_PCIE_fused"
      },
      {
        "netclass": "12V",
        "pattern": "/Supply/12V_aux"
      },
      {
        "netclass": "12V",
        "pattern": "/Supply/12V_aux_fused"
      },
      {
        "netclass": "12V",
        "pattern": "VDC"
      },
      {
        "netclass": "50Ohm-se",
        "pattern": "/Ethernet/ETH.MDC"
      },
      {
        "netclass": "50Ohm-se",
        "pattern": "/Ethernet/ETH.MDIO"
      },
      {
        "netclass": "50Ohm-se",
        "pattern": "/Ethernet/ETH.REF_CLK"
      },
      {
        "netclass": "50Ohm-se",
        "pattern": "/Ethernet/ETH.RXC"
      },
      {
        "netclass": "50Ohm-se",
        "pattern": "/Ethernet/ETH.RXD0"
      },
      {
        "netclass": "50Ohm-se",
        "pattern": "/Ethernet/ETH.RXD1"
      },
      {
        "netclass": "50Ohm-se",
        "pattern": "/Ethernet/ETH.RXD2"
      },
      {
        "netclass": "50Ohm-se",
        "pattern": "/Ethernet/ETH.RXD3"
      },
      {
        "netclass": "50Ohm-se",
        "pattern": "/Ethernet/ETH.RX_CTL"
      },
      {
        "netclass": "50Ohm-se",
        "pattern": "/Ethernet/ETH.TXC"
      },
      {
        "netclass": "50Ohm-se",
        "pattern": "/Ethernet/ETH.TXD0"
      },
      {
        "netclass": "50Ohm-se",
        "pattern": "/Ethernet/ETH.TXD1"
      },
      {
        "netclass": "50Ohm-se",
        "pattern": "/Ethernet/ETH.TXD2"
      },
      {
        "netclass": "50Ohm-se",
        "pattern": "/Ethernet/ETH.TXD3"
      },
      {
        "netclass": "50Ohm-se",
        "pattern": "/Ethernet/ETH.TX_CTL"
      },
      {
        "netclass": "50Ohm-se",
        "pattern": "/Ethernet/ETH.~{INT}"
      },
      {
        "netclass": "50Ohm-se",
        "pattern": "/Ethernet/ETH.~{RESET}"
      },
      {
        "netclass": "50Ohm-se",
        "pattern": "/FPGA Config/FLASH.IO0"
      },
      {
        "netclass": "50Ohm-se",
        "pattern": "/FPGA Config/FLASH.IO1"
      },
      {
        "netclass": "50Ohm-se",
        "pattern": "/FPGA Config/FLASH.IO2"
      },
      {
        "netclass": "50Ohm-se",
        "pattern": "/FPGA Config/FLASH.IO3"
      },
      {
        "netclass": "50Ohm-se",
        "pattern": "/FPGA Config/FLASH.SCK"
      },
      {
        "netclass": "50Ohm-se",
        "pattern": "/FPGA Config/FLASH.~{CS}"
      },
      {
        "netclass": "50Ohm-se",
        "pattern": "/FPGA bank 12/HyperRAM.DQ0"
      },
      {
        "netclass": "50Ohm-se",
        "pattern": "/FPGA bank 12/HyperRAM.DQ1"
      },
      {
        "netclass": "50Ohm-se",
        "pattern": "/FPGA bank 12/HyperRAM.DQ2"
      },
      {
        "netclass": "50Ohm-se",
        "pattern": "/FPGA bank 12/HyperRAM.DQ3"
      },
      {
        "netclass": "50Ohm-se",
        "pattern": "/FPGA bank 12/HyperRAM.DQ4"
      },
      {
        "netclass": "50Ohm-se",
        "pattern": "/FPGA bank 12/HyperRAM.DQ5"
      },
      {
        "netclass": "50Ohm-se",
        "pattern": "/FPGA bank 12/HyperRAM.DQ6"
      },
      {
        "netclass": "50Ohm-se",
        "pattern": "/FPGA bank 12/HyperRAM.DQ7"
      },
      {
        "netclass": "50Ohm-se",
        "pattern": "/FPGA bank 12/HyperRAM.RWDS"
      },
      {
        "netclass": "50Ohm-se",
        "pattern": "/FPGA bank 12/HyperRAM.~{CS}"
      },
      {
        "netclass": "50Ohm-se",
        "pattern": "/FPGA bank 12/HyperRAM.~{RESET}"
      },
      {
        "netclass": "50Ohm-se",
        "pattern": "/FPGA bank 16/GCLK100"
      },
      {
        "netclass": "50Ohm-se",
        "pattern": "/FPGA bank 16/SD.CD"
      },
      {
        "netclass": "50Ohm-se",
        "pattern": "/FPGA bank 16/SD.CLK"
      },
      {
        "netclass": "50Ohm-se",
        "pattern": "/FPGA bank 16/SD.CMD"
      },
      {
        "netclass": "50Ohm-se",
        "pattern": "/FPGA bank 16/SD.DAT0"
      },
      {
        "netclass": "50Ohm-se",
        "pattern": "/FPGA bank 16/SD.DAT1"
      },
      {
        "netclass": "50Ohm-se",
        "pattern": "/FPGA bank 16/SD.DAT2"
      },
      {
        "netclass": "50Ohm-se",
        "pattern": "/FPGA bank 16/SD.DAT3"
      },
      {
        "netclass": "50Ohm-se",
        "pattern": "/HyperRAM + QSPI Flash/IO0"
      },
      {
        "netclass": "50Ohm-se",
        "pattern": "/HyperRAM + QSPI Flash/IO1"
      },
      {
        "netclass": "50Ohm-se",
        "pattern": "/HyperRAM + QSPI Flash/IO2"
      },
      {
        "netclass": "50Ohm-se",
        "pattern": "/HyperRAM + QSPI Flash/IO3"
      },
      {
        "netclass": "85Ohm-diff_PCIe",
        "pattern": "/FPGA MGT Interface/GTR_REFCLK0_N"
      },
      {
        "netclass": "85Ohm-diff_PCIe",
        "pattern": "/FPGA MGT Interface/GTR_REFCLK0_P"
      },
      {
        "netclass": "85Ohm-diff_PCIe",
        "pattern": "/FPGA MGT Interface/GTX_TX0_N"
      },
      {
        "netclass": "85Ohm-diff_PCIe",
        "pattern": "/FPGA MGT Interface/GTX_TX0_P"
      },
      {
        "netclass": "85Ohm-diff_PCIe",
        "pattern": "/FPGA MGT Interface/GTX_TX1_N"
      },
      {
        "netclass": "85Ohm-diff_PCIe",
        "pattern": "/FPGA MGT Interface/GTX_TX1_P"
      },
      {
        "netclass": "85Ohm-diff_PCIe",
        "pattern": "/FPGA MGT Interface/GTX_TX2_N"
      },
      {
        "netclass": "85Ohm-diff_PCIe",
        "pattern": "/FPGA MGT Interface/GTX_TX2_P"
      },
      {
        "netclass": "85Ohm-diff_PCIe",
        "pattern": "/FPGA MGT Interface/GTX_TX3_N"
      },
      {
        "netclass": "85Ohm-diff_PCIe",
        "pattern": "/FPGA MGT Interface/GTX_TX3_P"
      },
      {
        "netclass": "85Ohm-diff_PCIe",
        "pattern": "/FPGA MGT Interface/PCIE.CLK_N"
      },
      {
        "netclass": "85Ohm-diff_PCIe",
        "pattern": "/FPGA MGT Interface/PCIE.CLK_P"
      },
      {
        "netclass": "85Ohm-diff_PCIe",
        "pattern": "/FPGA MGT Interface/PCIE.RXD0_N"
      },
      {
        "netclass": "85Ohm-diff_PCIe",
        "pattern": "/FPGA MGT Interface/PCIE.RXD0_P"
      },
      {
        "netclass": "85Ohm-diff_PCIe",
        "pattern": "/FPGA MGT Interface/PCIE.RXD1_N"
      },
      {
        "netclass": "85Ohm-diff_PCIe",
        "pattern": "/FPGA MGT Interface/PCIE.RXD1_P"
      },
      {
        "netclass": "85Ohm-diff_PCIe",
        "pattern": "/FPGA MGT Interface/PCIE.RXD2_N"
      },
      {
        "netclass": "85Ohm-diff_PCIe",
        "pattern": "/FPGA MGT Interface/PCIE.RXD2_P"
      },
      {
        "netclass": "85Ohm-diff_PCIe",
        "pattern": "/FPGA MGT Interface/PCIE.RXD3_N"
      },
      {
        "netclass": "85Ohm-diff_PCIe",
        "pattern": "/FPGA MGT Interface/PCIE.RXD3_P"
      },
      {
        "netclass": "85Ohm-diff_PCIe",
        "pattern": "/FPGA MGT Interface/PCIE.TXD0_N"
      },
      {
        "netclass": "85Ohm-diff_PCIe",
        "pattern": "/FPGA MGT Interface/PCIE.TXD0_P"
      },
      {
        "netclass": "85Ohm-diff_PCIe",
        "pattern": "/FPGA MGT Interface/PCIE.TXD1_N"
      },
      {
        "netclass": "85Ohm-diff_PCIe",
        "pattern": "/FPGA MGT Interface/PCIE.TXD1_P"
      },
      {
        "netclass": "85Ohm-diff_PCIe",
        "pattern": "/FPGA MGT Interface/PCIE.TXD2_N"
      },
      {
        "netclass": "85Ohm-diff_PCIe",
        "pattern": "/FPGA MGT Interface/PCIE.TXD2_P"
      },
      {
        "netclass": "85Ohm-diff_PCIe",
        "pattern": "/FPGA MGT Interface/PCIE.TXD3_N"
      },
      {
        "netclass": "85Ohm-diff_PCIe",
        "pattern": "/FPGA MGT Interface/PCIE.TXD3_P"
      },
      {
        "netclass": "90Ohm-diff",
        "pattern": "/Debug FTDI/DBG_USB_N"
      },
      {
        "netclass": "90Ohm-diff",
        "pattern": "/Debug FTDI/DBG_USB_P"
      },
      {
        "netclass": "Supply",
        "pattern": "+1V0"
      },
      {
        "netclass": "Supply",
        "pattern": "+1V0_MGTAVCC"
      },
      {
        "netclass": "Supply",
        "pattern": "+1V1"
      },
      {
        "netclass": "Supply",
        "pattern": "+1V2"
      },
      {
        "netclass": "Supply",
        "pattern": "+1V2_MGTAVTT"
      },
      {
        "netclass": "Supply",
        "pattern": "+1V8"
      },
      {
        "netclass": "Supply",
        "pattern": "+3V3"
      },
      {
        "netclass": "Supply",
        "pattern": "+3V3_AON"
      },
      {
        "netclass": "Supply",
        "pattern": "+5V"
      },
      {
        "netclass": "Supply",
        "pattern": "/Debug FTDI/VBUS"
      },
      {
        "netclass": "Supply",
        "pattern": "/Ethernet/AVDDH"
      },
      {
        "netclass": "Supply",
        "pattern": "/Ethernet/AVDDL"
      },
      {
        "netclass": "Supply",
        "pattern": "/Ethernet/AVDDL_PLL"
      },
      {
        "netclass": "Supply",
        "pattern": "/Supply/1V0_BS"
      },
      {
        "netclass": "Supply",
        "pattern": "/Supply/1V0_FB"
      },
      {
        "netclass": "Supply",
        "pattern": "/Supply/1V0_REG"
      },
      {
        "netclass": "Supply",
        "pattern": "/Supply/1V0_SS"
      },
      {
        "netclass": "Supply",
        "pattern": "/Supply/1V0_SW"
      },
      {
        "netclass": "Supply",
        "pattern": "/Supply/1V0_VCC"
      },
      {
        "netclass": "Supply",
        "pattern": "/Supply/1V1_SEN_+"
      },
      {
        "netclass": "Supply",
        "pattern": "/Supply/1V1_SEN_-"
      },
      {
        "netclass": "Supply",
        "pattern": "/Supply/1V1_local"
      },
      {
        "netclass": "Supply",
        "pattern": "/Supply/1V2_SEN_+"
      },
      {
        "netclass": "Supply",
        "pattern": "/Supply/1V2_SEN_-"
      },
      {
        "netclass": "Supply",
        "pattern": "/Supply/1V2_local"
      },
      {
        "netclass": "Supply",
        "pattern": "/Supply/1V7"
      },
      {
        "netclass": "Supply",
        "pattern": "/Supply/1V7_SEN_+"
      },
      {
        "netclass": "Supply",
        "pattern": "/Supply/1V7_SEN_-"
      },
      {
        "netclass": "Supply",
        "pattern": "/Supply/1V7_local"
      },
      {
        "netclass": "Supply",
        "pattern": "/Supply/1V8_SEN_+"
      },
      {
        "netclass": "Supply",
        "pattern": "/Supply/1V8_SEN_-"
      },
      {
        "netclass": "Supply",
        "pattern": "/Supply/1V8_local"
      },
      {
        "netclass": "Supply",
        "pattern": "/Supply/3V3_SEN_+"
      },
      {
        "netclass": "Supply",
        "pattern": "/Supply/3V3_SEN_-"
      },
      {
        "netclass": "Supply",
        "pattern": "/Supply/3V3_local"
      },
      {
        "netclass": "Supply",
        "pattern": "/Supply/5V_SEN_+"
      },
      {
        "netclass": "Supply",
        "pattern": "/Supply/5V_SEN_-"
      },
      {
        "netclass": "Supply",
        "pattern": "/Supply/5V_local"
      },
      {
        "netclass": "Supply",
        "pattern": "/Supply/spare"
      },
      {
        "netclass": "Supply",
        "pattern": "/Supply/spare_local"
      },
      {
        "netclass": "Supply",
        "pattern": "DAC_VREF"
      },
      {
        "netclass": "Supply",
        "pattern": "GND"
      },
      {
        "netclass": "85Ohm-diff_PCIe",
        "pattern": "*GTY*"
      },
      {
        "netclass": "85Ohm-diff_PCIe",
        "pattern": "*PCIE.*"
      },
      {
        "netclass": "40Ohm-se_DQ",
        "pattern": "/DDR5 RDIMM/..DQ.?."
      },
      {
        "netclass": "80Ohm-diff_DQS",
        "pattern": "/DDR5 RDIMM/?.DQS*"
      },
      {
        "netclass": "50Ohm-se",
        "pattern": "/DDR5 RDIMM/?.CA*"
      },
      {
        "netclass": "100Ohm-diff",
        "pattern": "/DDR5 RDIMM/*CK*"
      },
      {
        "netclass": "40Ohm-se_DQ",
        "pattern": "/DDR5 RDIMM/CTRL.*DQ*"
      },
      {
        "netclass": "40Ohm-se_DQ",
        "pattern": "/DDR5 RDIMM/?.CB*"
      },
      {
        "netclass": "100Ohm-diff",
        "pattern": "/FPGA MGT Interface/HDMI_OUT.*"
      },
      {
        "netclass": "100Ohm-diff",
        "pattern": "/FPGA MGT Interface/HDMI_IN.*"
      },
      {
        "netclass": "100Ohm-diff",
        "pattern": "*HDMI_FPGA.RX*"
      },
      {
        "netclass": "100Ohm-diff",
        "pattern": "*HDMI_REC_CLK*"
      },
      {
        "netclass": "100Ohm-diff",
        "pattern": "*GCLK*"
      }
    ]
  },
  "pcbnew": {
    "last_paths": {
      "gencad": "",
      "idf": "",
      "netlist": "",
      "plot": "",
      "pos_files": "",
      "specctra_dsn": "",
      "step": "",
      "svg": "",
      "vrml": "data-center-rdimm-ddr4-tester.wrl"
    },
    "page_layout_descr_file": ""
  },
  "schematic": {
    "annotate_start_num": 0,
    "bom_export_filename": "",
    "bom_fmt_presets": [],
    "bom_fmt_settings": {
      "field_delimiter": ",",
      "keep_line_breaks": false,
      "keep_tabs": false,
      "name": "CSV",
      "ref_delimiter": ",",
      "ref_range_delimiter": "",
      "string_delimiter": "\""
    },
    "bom_presets": [],
    "bom_settings": {
      "exclude_dnp": false,
      "fields_ordered": [
        {
          "group_by": false,
          "label": "Reference",
          "name": "Reference",
          "show": true
        },
        {
          "group_by": true,
          "label": "Value",
          "name": "Value",
          "show": true
        },
        {
          "group_by": false,
          "label": "Datasheet",
          "name": "Datasheet",
          "show": true
        },
        {
          "group_by": false,
          "label": "Footprint",
          "name": "Footprint",
          "show": true
        },
        {
          "group_by": false,
          "label": "Qty",
          "name": "${QUANTITY}",
          "show": true
        },
        {
          "group_by": true,
          "label": "DNP",
          "name": "${DNP}",
          "show": true
        }
      ],
      "filter_string": "",
      "group_symbols": true,
      "include_excluded_from_bom": false,
      "name": "Grouped By Value",
      "sort_asc": true,
      "sort_field": "Reference"
    },
    "connection_grid_size": 50.0,
    "drawing": {
      "dashed_lines_dash_length_ratio": 12.0,
      "dashed_lines_gap_length_ratio": 3.0,
      "default_line_thickness": 6.0,
      "default_text_size": 50.0,
      "field_names": [],
      "intersheets_ref_own_page": false,
      "intersheets_ref_prefix": "Pg. ",
      "intersheets_ref_short": false,
      "intersheets_ref_show": true,
      "intersheets_ref_suffix": "",
      "junction_size_choice": 3,
      "label_size_ratio": 0.25,
      "operating_point_overlay_i_precision": 3,
      "operating_point_overlay_i_range": "~A",
      "operating_point_overlay_v_precision": 3,
      "operating_point_overlay_v_range": "~V",
      "overbar_offset_ratio": 1.23,
      "pin_symbol_size": 0.0,
      "text_offset_ratio": 0.08
    },
    "legacy_lib_dir": "",
    "legacy_lib_list": [],
    "meta": {
      "version": 1
    },
    "net_format_name": "Pcbnew",
    "ngspice": {
      "fix_include_paths": true,
      "fix_passive_vals": false,
      "meta": {
        "version": 0
      },
      "model_mode": 0,
      "workbook_filename": ""
    },
    "page_layout_descr_file": "",
    "plot_directory": "./doc",
    "space_save_all_events": true,
    "spice_adjust_passive_values": false,
    "spice_current_sheet_as_root": false,
    "spice_external_command": "spice \"%I\"",
    "spice_model_current_sheet_as_root": true,
    "spice_save_all_currents": false,
    "spice_save_all_dissipations": false,
    "spice_save_all_voltages": false,
    "subpart_first_id": 65,
    "subpart_id_separator": 0
  },
  "sheets": [
    [
      "",
      "Root"
    ],
    [
      "",
      "HyperRAM + QSPI Flash"
    ],
    [
      "",
      "FPGA Config"
    ],
    [
      "",
      "DDR5 RDIMM"
    ],
    [
      "",
      "FPGA power"
    ],
    [
      "",
      "Debug FTDI + VNA"
    ],
    [
      "",
      "Ethernet"
    ],
    [
      "",
      "FPGA banks HP"
    ],
    [
      "",
      "Supply"
    ],
    [
      "",
      "FPGA MGT Interface"
    ],
    [
      "",
      "PCIe connector"
    ],
    [
      "",
      "FPGA banks HD"
    ],
    [
      "",
      "I^{2}C + I3C"
    ],
    [
      "",
      "HDMI + SD Card"
    ],
    [
      "",
      "DC-DC VCCINT"
    ],
    [
      "",
      "DC-DC AUX, MGT"
    ],
    [
      "",
      "DC-DC IO"
    ]
  ],
  "text_variables": {}
}
